# S9S_MB_2U (Grand Teton) — schematic netlist excerpt (pin names and nets, part order shuffled) for the footprints in the layout excerpt that follows; sources: Cadence DE-HDL packaged netlist, KiCad conversion of 03242023_DA0F0TMBIJ0_F0T_Motherboard_J_brd_V01_OCP.brd

C948  Q_CAP_DIFFBUS  DIFF BUS_0.22UF 6.3V 20% X6S  pkg C0201  page 173 : \1\ = P5E_CPU0_PE2_TX_C_DN<8> ; \2\ = P5E_CPU0_PE2_TX_DN<8>

U218  74LVC1G07GV  IC  pkg SC-74A_2-9X1-5  page 161
  NC1  = NC_U218_NC1
  A  = FM_SYS_THROTTLE_R_N
  GND  = GND
  Y  = OCP_V3_2_PWRBRK_BUFF_N
  VCC  = P3V3_AUX

D6  Q_LED  IC  pkg SMLF  page 218 : A = LED_CPU_RMCA_CATERR ; C = GND

(kicad_pcb
	(version 20260206)
	(generator "pcbnew")
	(generator_version "10.0")
	(general
		(thickness 1.6)
		(legacy_teardrops no)
	)
	(paper "A4")
	(title_block
		(title "03242023_DA0F0TMBIJ0_F0T_Motherboard_J_brd_V01_OCP.brd")
		(comment 1 "Grand Teton / footprints 2720-2722 of 6105")
	)
	(layers
		(0 "F.Cu" signal "TOP")
		(4 "In1.Cu" signal "GND")
		(6 "In2.Cu" signal "IN1")
		(8 "In3.Cu" signal "GND1")
		(10 "In4.Cu" signal "IN2")
		(12 "In5.Cu" signal "GND2")
		(14 "In6.Cu" signal "IN3")
		(16 "In7.Cu" signal "GND3")
		(18 "In8.Cu" signal "VCC")
		(20 "In9.Cu" signal "VCC1")
		(22 "In10.Cu" signal "GND4")
		(24 "In11.Cu" signal "IN4")
		(26 "In12.Cu" signal "GND5")
		(28 "In13.Cu" signal "IN5")
		(30 "In14.Cu" signal "GND6")
		(32 "In15.Cu" signal "IN6")
		(34 "In16.Cu" signal "GND7")
		(2 "B.Cu" signal "BOTTOM")
		(9 "F.Adhes" user "F.Adhesive")
		(11 "B.Adhes" user "B.Adhesive")
		(13 "F.Paste" user "Package Geometry/Pastemask Top")
		(15 "B.Paste" user "Package Geometry/Pastemask Bottom")
		(5 "F.SilkS" user "Ref Des/Silkscreen Top")
		(7 "B.SilkS" user "Ref Des/Silkscreen Bottom")
		(1 "F.Mask" user "Board Geometry/Soldermask Top")
		(3 "B.Mask" user "Board Geometry/Soldermask Bottom")
		(17 "Dwgs.User" user "User.Drawings")
		(19 "Cmts.User" user "User.Comments")
		(21 "Eco1.User" user "User.Eco1")
		(23 "Eco2.User" user "User.Eco2")
		(25 "Edge.Cuts" user "Board Geometry/Outline")
		(27 "Margin" user)
		(31 "F.CrtYd" user "Package Geometry/Place Bound Top")
		(29 "B.CrtYd" user "Package Geometry/Place Bound Bottom")
		(35 "F.Fab" user "Ref Des/Assembly Top")
		(33 "B.Fab" user "Ref Des/Assembly Bottom")
	)
	(footprint ""
		(layer "F.Cu")
		(at 196.67982 -80.617568)
		(property "Reference" "D6"
			(at -1.397 -1.24333 0)
			(unlocked yes)
			(layer "F.SilkS")
			(effects
				(font
					(size 0.7874 0.5842)
					(thickness 0.1524)
				)
				(justify left)
			)
		)
		(property "Value" ""
			(at 0 0 0)
			(layer "F.Fab")
			(effects
				(font
					(size 1.27 1.27)
				)
			)
		)
		(duplicate_pad_numbers_are_jumpers no)
		(fp_line
			(start -1.3208 -0.5588)
			(end 1.3208 -0.5588)
			(stroke
				(width 0.1524)
				(type default)
			)
			(layer "F.SilkS")
		)
		(fp_line
			(start -1.3208 0.5588)
			(end -1.3208 -0.5588)
			(stroke
				(width 0.1524)
				(type default)
			)
			(layer "F.SilkS")
		)
		(fp_line
			(start 1.3208 -0.5588)
			(end 1.3208 0.5588)
			(stroke
				(width 0.1524)
				(type default)
			)
			(layer "F.SilkS")
		)
		(fp_line
			(start 1.3208 0.5588)
			(end -1.3208 0.5588)
			(stroke
				(width 0.1524)
				(type default)
			)
			(layer "F.SilkS")
		)
		(fp_line
			(start 1.4732 -0.5588)
			(end 1.4732 0.5588)
			(stroke
				(width 0.1524)
				(type default)
			)
			(layer "F.SilkS")
		)
		(fp_line
			(start 1.6256 0.5588)
			(end 1.6256 -0.5588)
			(stroke
				(width 0.1524)
				(type default)
			)
			(layer "F.SilkS")
		)
		(fp_line
			(start 1.778 -0.5588)
			(end 1.3208 -0.5588)
			(stroke
				(width 0.1524)
				(type default)
			)
			(layer "F.SilkS")
		)
		(fp_line
			(start 1.778 -0.5588)
			(end 1.778 0.5588)
			(stroke
				(width 0.1524)
				(type default)
			)
			(layer "F.SilkS")
		)
		(fp_line
			(start 1.778 0.5588)
			(end 1.3208 0.5588)
			(stroke
				(width 0.1524)
				(type default)
			)
			(layer "F.SilkS")
		)
		(fp_line
			(start -0.899922 -0.40005)
			(end 0.899922 -0.40005)
			(stroke
				(width 0.1)
				(type default)
			)
			(layer "F.Fab")
		)
		(fp_line
			(start -0.899922 0.40005)
			(end -0.899922 -0.40005)
			(stroke
				(width 0.1)
				(type default)
			)
			(layer "F.Fab")
		)
		(fp_line
			(start 0.899922 -0.40005)
			(end 0.899922 0.40005)
			(stroke
				(width 0.1)
				(type default)
			)
			(layer "F.Fab")
		)
		(fp_line
			(start 0.899922 0.40005)
			(end -0.899922 0.40005)
			(stroke
				(width 0.1)
				(type default)
			)
			(layer "F.Fab")
		)
		(fp_text user "+"
			(at -2.8956 -1.23825 0)
			(unlocked yes)
			(layer "F.SilkS")
			(effects
				(font
					(size 1.905 1.4224)
					(thickness 0.1524)
				)
				(justify left)
			)
		)
		(fp_text user "-"
			(at 1.651 -0.22225 0)
			(unlocked yes)
			(layer "F.SilkS")
			(effects
				(font
					(size 1.905 1.4224)
					(thickness 0.1524)
				)
				(justify left)
			)
		)
		(fp_text user "+"
			(at -2.6162 -0.22225 0)
			(unlocked yes)
			(layer "F.Fab")
			(effects
				(font
					(size 1.905 1.4224)
					(thickness 0.1524)
				)
				(justify left)
			)
		)
		(fp_text user "-"
			(at 1.651 -0.22225 0)
			(unlocked yes)
			(layer "F.Fab")
			(effects
				(font
					(size 1.905 1.4224)
					(thickness 0.1524)
				)
				(justify left)
			)
		)
		(pad "A" smd rect
			(at -0.750062 0)
			(size 0.8128 0.8128)
			(layers "F.Cu" "F.Mask" "F.Paste")
			(net "LED_CPU_RMCA_CATERR")
		)
		(pad "C" smd rect
			(at 0.750062 0)
			(size 0.8128 0.8128)
			(layers "F.Cu" "F.Mask" "F.Paste")
			(net "GND")
		)
	)
	(footprint ""
		(layer "F.Cu")
		(at 393.75461 -402.371052 -90)
		(property "Reference" "C948"
			(at 0 0 270)
			(layer "F.SilkS")
			(hide yes)
			(effects
				(font
					(size 1.27 1.27)
				)
			)
		)
		(property "Value" ""
			(at 0 0 270)
			(layer "F.Fab")
			(effects
				(font
					(size 1.27 1.27)
				)
			)
		)
		(duplicate_pad_numbers_are_jumpers no)
		(fp_line
			(start -0.299974 0.150114)
			(end -0.299974 -0.150114)
			(stroke
				(width 0.1)
				(type default)
			)
			(layer "F.Fab")
		)
		(fp_line
			(start 0.299974 0.150114)
			(end -0.299974 0.150114)
			(stroke
				(width 0.1)
				(type default)
			)
			(layer "F.Fab")
		)
		(fp_line
			(start -0.299974 -0.150114)
			(end 0.299974 -0.150114)
			(stroke
				(width 0.1)
				(type default)
			)
			(layer "F.Fab")
		)
		(fp_line
			(start 0.299974 -0.150114)
			(end 0.299974 0.150114)
			(stroke
				(width 0.1)
				(type default)
			)
			(layer "F.Fab")
		)
		(pad "1" smd rect
			(at -0.2667 0 270)
			(size 0.3048 0.381)
			(layers "F.Cu" "F.Mask" "F.Paste")
			(net "P5E_CPU0_PE2_TX_C_DN<8>")
		)
		(pad "2" smd rect
			(at 0.2667 0 270)
			(size 0.3048 0.381)
			(layers "F.Cu" "F.Mask" "F.Paste")
			(net "P5E_CPU0_PE2_TX_DN<8>")
		)
	)
	(footprint ""
		(layer "F.Cu")
		(at 113.44656 -28.567634 90)
		(property "Reference" "U218"
			(at -0.191516 -5.00888 0)
			(unlocked yes)
			(layer "F.SilkS")
			(effects
				(font
					(size 0.7874 0.5842)
					(thickness 0.1524)
				)
				(justify left)
			)
		)
		(property "Value" ""
			(at 0 0 90)
			(layer "F.Fab")
			(effects
				(font
					(size 1.27 1.27)
				)
			)
		)
		(duplicate_pad_numbers_are_jumpers no)
		(fp_line
			(start 1.733296 -1.549908)
			(end 0.660908 -1.549908)
			(stroke
				(width 0.1524)
				(type default)
			)
			(layer "F.SilkS")
		)
		(fp_line
			(start 0.660908 -1.549908)
			(end 0 -0.889)
			(stroke
				(width 0.1524)
				(type default)
			)
			(layer "F.SilkS")
		)
		(fp_line
			(start -0.660908 -1.549908)
			(end -1.733296 -1.549908)
			(stroke
				(width 0.1524)
				(type default)
			)
			(layer "F.SilkS")
		)
		(fp_line
			(start -1.733296 -1.549908)
			(end -1.733296 1.549908)
			(stroke
				(width 0.1524)
				(type default)
			)
			(layer "F.SilkS")
		)
		(fp_line
			(start 0 -0.889)
			(end -0.660908 -1.549908)
			(stroke
				(width 0.1524)
				(type default)
			)
			(layer "F.SilkS")
		)
		(fp_line
			(start 1.733296 1.549908)
			(end 1.733296 -1.549908)
			(stroke
				(width 0.1524)
				(type default)
			)
			(layer "F.SilkS")
		)
		(fp_line
			(start -1.733296 1.549908)
			(end 1.733296 1.549908)
			(stroke
				(width 0.1524)
				(type default)
			)
			(layer "F.SilkS")
		)
		(fp_poly
			(pts
				(xy -0.982726 -2.387854) (xy -1.236726 -1.879854) (xy -1.490726 -2.387854)
			)
			(stroke
				(width 0)
				(type default)
			)
			(fill yes)
			(layer "F.SilkS")
		)
		(fp_line
			(start 0.849884 -1.549908)
			(end -0.849884 -1.549908)
			(stroke
				(width 0.1)
				(type default)
			)
			(layer "F.Fab")
		)
		(fp_line
			(start -0.849884 -1.549908)
			(end -0.849884 1.549908)
			(stroke
				(width 0.1)
				(type default)
			)
			(layer "F.Fab")
		)
		(fp_line
			(start 0.849884 1.549908)
			(end 0.849884 -1.549908)
			(stroke
				(width 0.1)
				(type default)
			)
			(layer "F.Fab")
		)
		(fp_line
			(start -0.849884 1.549908)
			(end 0.849884 1.549908)
			(stroke
				(width 0.1)
				(type default)
			)
			(layer "F.Fab")
		)
		(fp_poly
			(pts
				(xy -2.4384 -1.20396) (xy -2.4384 -0.69596) (xy -1.9304 -0.94996)
			)
			(stroke
				(width 0)
				(type default)
			)
			(fill yes)
			(layer "F.Fab")
		)
		(pad "1" smd rect
			(at -1.199896 -0.94996)
			(size 0.5588 0.8128)
			(layers "F.Cu" "F.Mask" "F.Paste")
			(net "NC_U218_NC1")
		)
		(pad "2" smd rect
			(at -1.199896 0)
			(size 0.5588 0.8128)
			(layers "F.Cu" "F.Mask" "F.Paste")
			(net "FM_SYS_THROTTLE_R_N")
		)
		(pad "3" smd rect
			(at -1.199896 0.94996)
			(size 0.5588 0.8128)
			(layers "F.Cu" "F.Mask" "F.Paste")
			(net "GND")
		)
		(pad "4" smd rect
			(at 1.199896 0.94996)
			(size 0.5588 0.8128)
			(layers "F.Cu" "F.Mask" "F.Paste")
			(net "OCP_V3_2_PWRBRK_BUFF_N")
		)
		(pad "5" smd rect
			(at 1.199896 -0.94996)
			(size 0.5588 0.8128)
			(layers "F.Cu" "F.Mask" "F.Paste")
			(net "P3V3_AUX")
		)
	)
)
